# S9S_MB_2U (Grand Teton) — schematic netlist excerpt (pin names and nets, part order shuffled) for the footprints in the layout excerpt that follows; sources: Cadence DE-HDL packaged netlist, KiCad conversion of 03242023_DA0F0TMBIJ0_F0T_Motherboard_J_brd_V01_OCP.brd

R3654  Q_RES  33.2 1% CHIP  pkg 0402LF  page 152 : A = RST_USB_HUB_N ; B = RST_USB_HUB_R_N
PC2345  Q_CAPP  270UF 16V 20% OSCON  pkg THLF  page 267 : A = SW_P12V_PVCCIN_CPU0_FLT ; B = GND
R4769  Q_RES  100K 1% CHIP  pkg 0402LF  page 245 : A = FM_PDB_BUF_EN_R ; B = GND

(kicad_pcb
	(version 20260206)
	(generator "pcbnew")
	(generator_version "10.0")
	(general
		(thickness 1.6)
		(legacy_teardrops no)
	)
	(paper "A4")
	(title_block
		(title "03242023_DA0F0TMBIJ0_F0T_Motherboard_J_brd_V01_OCP.brd")
		(comment 1 "Grand Teton / footprints 59-61 of 6105")
	)
	(layers
		(0 "F.Cu" signal "TOP")
		(4 "In1.Cu" signal "GND")
		(6 "In2.Cu" signal "IN1")
		(8 "In3.Cu" signal "GND1")
		(10 "In4.Cu" signal "IN2")
		(12 "In5.Cu" signal "GND2")
		(14 "In6.Cu" signal "IN3")
		(16 "In7.Cu" signal "GND3")
		(18 "In8.Cu" signal "VCC")
		(20 "In9.Cu" signal "VCC1")
		(22 "In10.Cu" signal "GND4")
		(24 "In11.Cu" signal "IN4")
		(26 "In12.Cu" signal "GND5")
		(28 "In13.Cu" signal "IN5")
		(30 "In14.Cu" signal "GND6")
		(32 "In15.Cu" signal "IN6")
		(34 "In16.Cu" signal "GND7")
		(2 "B.Cu" signal "BOTTOM")
		(9 "F.Adhes" user "F.Adhesive")
		(11 "B.Adhes" user "B.Adhesive")
		(13 "F.Paste" user "Package Geometry/Pastemask Top")
		(15 "B.Paste" user "Package Geometry/Pastemask Bottom")
		(5 "F.SilkS" user "Ref Des/Silkscreen Top")
		(7 "B.SilkS" user "Ref Des/Silkscreen Bottom")
		(1 "F.Mask" user "Board Geometry/Soldermask Top")
		(3 "B.Mask" user "Board Geometry/Soldermask Bottom")
		(17 "Dwgs.User" user "User.Drawings")
		(19 "Cmts.User" user "User.Comments")
		(21 "Eco1.User" user "User.Eco1")
		(23 "Eco2.User" user "User.Eco2")
		(25 "Edge.Cuts" user "Board Geometry/Outline")
		(27 "Margin" user)
		(31 "F.CrtYd" user "Package Geometry/Place Bound Top")
		(29 "B.CrtYd" user "Package Geometry/Place Bound Bottom")
		(35 "F.Fab" user "Ref Des/Assembly Top")
		(33 "B.Fab" user "Ref Des/Assembly Bottom")
	)
	(footprint ""
		(layer "F.Cu")
		(at 9.908032 -92.687648 90)
		(property "Reference" "R3654"
			(at 0 0 90)
			(layer "F.SilkS")
			(hide yes)
			(effects
				(font
					(size 1.27 1.27)
				)
			)
		)
		(property "Value" ""
			(at 0 0 90)
			(layer "F.Fab")
			(effects
				(font
					(size 1.27 1.27)
				)
			)
		)
		(duplicate_pad_numbers_are_jumpers no)
		(fp_line
			(start 0.7874 -0.4064)
			(end 0.7874 0.4064)
			(stroke
				(width 0.1524)
				(type default)
			)
			(layer "F.SilkS")
		)
		(fp_line
			(start -0.7874 -0.4064)
			(end 0.7874 -0.4064)
			(stroke
				(width 0.1524)
				(type default)
			)
			(layer "F.SilkS")
		)
		(fp_line
			(start 0.7874 0.4064)
			(end -0.7874 0.4064)
			(stroke
				(width 0.1524)
				(type default)
			)
			(layer "F.SilkS")
		)
		(fp_line
			(start -0.7874 0.4064)
			(end -0.7874 -0.4064)
			(stroke
				(width 0.1524)
				(type default)
			)
			(layer "F.SilkS")
		)
		(fp_line
			(start -0.12065 -0.305054)
			(end -0.12065 -0.2794)
			(stroke
				(width 0.1)
				(type default)
			)
			(layer "F.Fab")
		)
		(fp_line
			(start -0.67945 -0.305054)
			(end -0.12065 -0.305054)
			(stroke
				(width 0.1)
				(type default)
			)
			(layer "F.Fab")
		)
		(fp_line
			(start 0.67945 -0.3048)
			(end 0.67945 0.3048)
			(stroke
				(width 0.1)
				(type default)
			)
			(layer "F.Fab")
		)
		(fp_line
			(start 0.12065 -0.3048)
			(end 0.67945 -0.3048)
			(stroke
				(width 0.1)
				(type default)
			)
			(layer "F.Fab")
		)
		(fp_line
			(start 0.12065 -0.2794)
			(end 0.12065 -0.3048)
			(stroke
				(width 0.1)
				(type default)
			)
			(layer "F.Fab")
		)
		(fp_line
			(start -0.12065 -0.2794)
			(end 0.12065 -0.2794)
			(stroke
				(width 0.1)
				(type default)
			)
			(layer "F.Fab")
		)
		(fp_line
			(start 0.120396 0.2794)
			(end -0.12065 0.2794)
			(stroke
				(width 0.1)
				(type default)
			)
			(layer "F.Fab")
		)
		(fp_line
			(start -0.12065 0.2794)
			(end -0.12065 0.3048)
			(stroke
				(width 0.1)
				(type default)
			)
			(layer "F.Fab")
		)
		(fp_line
			(start 0.67945 0.3048)
			(end 0.120396 0.3048)
			(stroke
				(width 0.1)
				(type default)
			)
			(layer "F.Fab")
		)
		(fp_line
			(start 0.120396 0.3048)
			(end 0.120396 0.2794)
			(stroke
				(width 0.1)
				(type default)
			)
			(layer "F.Fab")
		)
		(fp_line
			(start -0.12065 0.3048)
			(end -0.67945 0.3048)
			(stroke
				(width 0.1)
				(type default)
			)
			(layer "F.Fab")
		)
		(fp_line
			(start -0.67945 0.3048)
			(end -0.67945 -0.305054)
			(stroke
				(width 0.1)
				(type default)
			)
			(layer "F.Fab")
		)
		(pad "1" smd circle
			(at -0.40005 0 90)
			(size 0 0)
			(layers "F.Cu" "F.Mask" "F.Paste")
			(net "RST_USB_HUB_N")
		)
		(pad "2" smd circle
			(at 0.40005 0 90)
			(size 0 0)
			(layers "F.Cu" "F.Mask" "F.Paste")
			(net "RST_USB_HUB_R_N")
		)
	)
	(footprint ""
		(layer "F.Cu")
		(at 182.964582 -425.831)
		(property "Reference" "R4769"
			(at 0 0 0)
			(layer "F.SilkS")
			(hide yes)
			(effects
				(font
					(size 1.27 1.27)
				)
			)
		)
		(property "Value" ""
			(at 0 0 0)
			(layer "F.Fab")
			(effects
				(font
					(size 1.27 1.27)
				)
			)
		)
		(duplicate_pad_numbers_are_jumpers no)
		(fp_line
			(start -0.7874 -0.4064)
			(end 0.7874 -0.4064)
			(stroke
				(width 0.1524)
				(type default)
			)
			(layer "F.SilkS")
		)
		(fp_line
			(start -0.7874 0.4064)
			(end -0.7874 -0.4064)
			(stroke
				(width 0.1524)
				(type default)
			)
			(layer "F.SilkS")
		)
		(fp_line
			(start 0.7874 -0.4064)
			(end 0.7874 0.4064)
			(stroke
				(width 0.1524)
				(type default)
			)
			(layer "F.SilkS")
		)
		(fp_line
			(start 0.7874 0.4064)
			(end -0.7874 0.4064)
			(stroke
				(width 0.1524)
				(type default)
			)
			(layer "F.SilkS")
		)
		(fp_line
			(start -0.67945 -0.305054)
			(end -0.12065 -0.305054)
			(stroke
				(width 0.1)
				(type default)
			)
			(layer "F.Fab")
		)
		(fp_line
			(start -0.67945 0.3048)
			(end -0.67945 -0.305054)
			(stroke
				(width 0.1)
				(type default)
			)
			(layer "F.Fab")
		)
		(fp_line
			(start -0.12065 -0.305054)
			(end -0.12065 -0.2794)
			(stroke
				(width 0.1)
				(type default)
			)
			(layer "F.Fab")
		)
		(fp_line
			(start -0.12065 -0.2794)
			(end 0.12065 -0.2794)
			(stroke
				(width 0.1)
				(type default)
			)
			(layer "F.Fab")
		)
		(fp_line
			(start -0.12065 0.2794)
			(end -0.12065 0.3048)
			(stroke
				(width 0.1)
				(type default)
			)
			(layer "F.Fab")
		)
		(fp_line
			(start -0.12065 0.3048)
			(end -0.67945 0.3048)
			(stroke
				(width 0.1)
				(type default)
			)
			(layer "F.Fab")
		)
		(fp_line
			(start 0.120396 0.2794)
			(end -0.12065 0.2794)
			(stroke
				(width 0.1)
				(type default)
			)
			(layer "F.Fab")
		)
		(fp_line
			(start 0.120396 0.3048)
			(end 0.120396 0.2794)
			(stroke
				(width 0.1)
				(type default)
			)
			(layer "F.Fab")
		)
		(fp_line
			(start 0.12065 -0.3048)
			(end 0.67945 -0.3048)
			(stroke
				(width 0.1)
				(type default)
			)
			(layer "F.Fab")
		)
		(fp_line
			(start 0.12065 -0.2794)
			(end 0.12065 -0.3048)
			(stroke
				(width 0.1)
				(type default)
			)
			(layer "F.Fab")
		)
		(fp_line
			(start 0.67945 -0.3048)
			(end 0.67945 0.3048)
			(stroke
				(width 0.1)
				(type default)
			)
			(layer "F.Fab")
		)
		(fp_line
			(start 0.67945 0.3048)
			(end 0.120396 0.3048)
			(stroke
				(width 0.1)
				(type default)
			)
			(layer "F.Fab")
		)
		(pad "1" smd circle
			(at -0.40005 0)
			(size 0 0)
			(layers "F.Cu" "F.Mask" "F.Paste")
			(net "FM_PDB_BUF_EN_R")
		)
		(pad "2" smd circle
			(at 0.40005 0)
			(size 0 0)
			(layers "F.Cu" "F.Mask" "F.Paste")
			(net "GND")
		)
	)
	(footprint ""
		(layer "F.Cu")
		(at 364.2868 -350.357948 90)
		(property "Reference" "PC2345"
			(at 0 0 90)
			(layer "F.SilkS")
			(hide yes)
			(effects
				(font
					(size 1.27 1.27)
				)
			)
		)
		(property "Value" ""
			(at 0 0 90)
			(layer "F.Fab")
			(effects
				(font
					(size 1.27 1.27)
				)
			)
		)
		(duplicate_pad_numbers_are_jumpers no)
		(fp_line
			(start -3.400044 1.249934)
			(end 3.400044 1.249934)
			(stroke
				(width 0.1524)
				(type default)
			)
			(layer "F.SilkS")
		)
		(fp_circle
			(center 0 1.249934)
			(end 0 4.649978)
			(stroke
				(width 0.1524)
				(type default)
			)
			(fill no)
			(layer "F.SilkS")
		)
		(fp_poly
			(pts
				(arc
					(start -3.400044 1.249934)
					(mid 0 4.649978)
					(end 3.400044 1.249934)
				)
			)
			(stroke
				(width 0)
				(type default)
			)
			(fill yes)
			(layer "F.SilkS")
		)
		(fp_circle
			(center 0 1.249934)
			(end 0 4.649978)
			(stroke
				(width 0.1)
				(type default)
			)
			(fill no)
			(layer "F.Fab")
		)
		(pad "1" thru_hole rect
			(at 0 0 90)
			(size 1.524 1.524)
			(drill 1.016)
			(layers "*.Cu" "*.Mask")
			(remove_unused_layers no)
			(net "SW_P12V_PVCCIN_CPU0_FLT")
			(clearance 0)
			(padstack
				(mode front_inner_back)
				(layer "Inner"
					(shape circle)
					(size 1.524 1.524)
					(clearance 0)
				)
				(layer "B.Cu"
					(shape rect)
					(size 1.524 1.524)
					(clearance 0)
				)
			)
		)
		(pad "2" thru_hole circle
			(at 0 2.500122 90)
			(size 1.524 1.524)
			(drill 1.016)
			(layers "*.Cu" "*.Mask")
			(remove_unused_layers no)
			(net "GND")
			(clearance 0)
		)
	)
)
